(kicad_pcb
	(version 20260206)
	(generator "pcbnew")
	(generator_version "10.0")
	(general
		(thickness 1.6)
		(legacy_teardrops no)
	)
	(paper "A4")
	(title_block
		(title "Wiwynn_Tioga_Pass_MB.brd")
		(comment 1 "Tioga Pass / footprints 3255-3261 of 4770")
	)
	(layers
		(0 "F.Cu" signal "TOP")
		(4 "In1.Cu" signal "L2GND")
		(6 "In2.Cu" signal "L3")
		(8 "In3.Cu" signal "L4GND")
		(10 "In4.Cu" signal "L5")
		(12 "In5.Cu" signal "L6GND")
		(14 "In6.Cu" signal "L7VCC")
		(16 "In7.Cu" signal "L8VCC")
		(18 "In8.Cu" signal "L9GND")
		(20 "In9.Cu" signal "L10")
		(22 "In10.Cu" signal "L11GND")
		(24 "In11.Cu" signal "L12")
		(26 "In12.Cu" signal "L13GND")
		(2 "B.Cu" signal "BOTTOM")
		(9 "F.Adhes" user "F.Adhesive")
		(11 "B.Adhes" user "B.Adhesive")
		(13 "F.Paste" user "Package Geometry/Pastemask Top")
		(15 "B.Paste" user "Package Geometry/Pastemask Bottom")
		(5 "F.SilkS" user "Ref Des/Silkscreen Top")
		(7 "B.SilkS" user "Ref Des/Silkscreen Bottom")
		(1 "F.Mask" user "Board Geometry/Soldermask Top")
		(3 "B.Mask" user "Board Geometry/Soldermask Bottom")
		(17 "Dwgs.User" user "User.Drawings")
		(19 "Cmts.User" user "User.Comments")
		(21 "Eco1.User" user "User.Eco1")
		(23 "Eco2.User" user "User.Eco2")
		(25 "Edge.Cuts" user "Board Geometry/Outline")
		(27 "Margin" user)
		(31 "F.CrtYd" user "Package Geometry/Place Bound Top")
		(29 "B.CrtYd" user "Package Geometry/Place Bound Bottom")
		(35 "F.Fab" user "Ref Des/Assembly Top")
		(33 "B.Fab" user "Ref Des/Assembly Bottom")
	)
	(footprint ""
		(layer "B.Cu")
		(at 373.6975 -56.769 -90)
		(property "Reference" "R3P59"
			(at 0 0 90)
			(layer "B.SilkS")
			(hide yes)
			(effects
				(font
					(size 1.27 1.27)
				)
				(justify mirror)
			)
		)
		(property "Value" ""
			(at 0 0 90)
			(layer "B.Fab")
			(effects
				(font
					(size 1.27 1.27)
				)
				(justify mirror)
			)
		)
		(duplicate_pad_numbers_are_jumpers no)
		(fp_poly
			(pts
				(xy 0.2794 -0.1016) (xy -0.2794 -0.1016) (xy -0.2794 0.9906) (xy 0.2794 0.9906)
			)
			(stroke
				(width 0)
				(type default)
			)
			(fill no)
			(layer "B.CrtYd")
		)
		(fp_line
			(start -0.2794 0.9906)
			(end -0.2794 -0.1016)
			(stroke
				(width 0.1)
				(type default)
			)
			(layer "B.Fab")
		)
		(fp_line
			(start 0.2794 0.9906)
			(end -0.2794 0.9906)
			(stroke
				(width 0.1)
				(type default)
			)
			(layer "B.Fab")
		)
		(fp_line
			(start -0.2794 -0.1016)
			(end 0.2794 -0.1016)
			(stroke
				(width 0.1)
				(type default)
			)
			(layer "B.Fab")
		)
		(fp_line
			(start 0.2794 -0.1016)
			(end 0.2794 0.9906)
			(stroke
				(width 0.1)
				(type default)
			)
			(layer "B.Fab")
		)
		(pad "1" smd rect
			(at 0 0 90)
			(size 0.508 0.508)
			(layers "B.Cu" "B.Mask" "B.Paste")
			(net "H_CPU0_CATERR_G_N")
		)
		(pad "2" smd rect
			(at 0 0.889 90)
			(size 0.508 0.508)
			(layers "B.Cu" "B.Mask" "B.Paste")
			(net "H_CPU_CATERR_G_N")
		)
		(zone
			(layer "B.Cu")
			(hatch none 0.5)
			(connect_pads
				(clearance 0)
			)
			(min_thickness 0.25)
			(keepout
				(tracks not_allowed)
				(vias allowed)
				(pads allowed)
				(copperpour not_allowed)
				(footprints allowed)
			)
			(placement
				(enabled no)
				(sheetname "")
			)
			(fill
				(thermal_gap 0.5)
				(thermal_bridge_width 0.5)
				(island_removal_mode 0)
			)
			(polygon
				(pts
					(xy 373.0625 -56.515) (xy 373.0625 -57.023) (xy 373.4435 -57.023) (xy 373.4435 -56.515)
				)
			)
		)
		(zone
			(layer "B.Cu")
			(hatch none 0.5)
			(connect_pads
				(clearance 0)
			)
			(min_thickness 0.25)
			(keepout
				(tracks allowed)
				(vias not_allowed)
				(pads allowed)
				(copperpour not_allowed)
				(footprints allowed)
			)
			(placement
				(enabled no)
				(sheetname "")
			)
			(fill
				(thermal_gap 0.5)
				(thermal_bridge_width 0.5)
				(island_removal_mode 0)
			)
			(polygon
				(pts
					(xy 373.4435 -56.515) (xy 373.4435 -57.023) (xy 373.0625 -57.023) (xy 373.0625 -56.515)
				)
			)
		)
	)
	(footprint ""
		(layer "B.Cu")
		(at 441.3504 -52.2986)
		(property "Reference" "C2R9"
			(at 0 0 0)
			(layer "B.SilkS")
			(hide yes)
			(effects
				(font
					(size 1.27 1.27)
				)
				(justify mirror)
			)
		)
		(property "Value" ""
			(at 0 0 0)
			(layer "B.Fab")
			(effects
				(font
					(size 1.27 1.27)
				)
				(justify mirror)
			)
		)
		(duplicate_pad_numbers_are_jumpers no)
		(fp_poly
			(pts
				(xy -0.3048 -0.1016) (xy -0.3048 0.9906) (xy 0.3048 0.9906) (xy 0.3048 -0.1016)
			)
			(stroke
				(width 0)
				(type default)
			)
			(fill no)
			(layer "B.CrtYd")
		)
		(fp_line
			(start -0.3048 -0.1016)
			(end 0.3048 -0.1016)
			(stroke
				(width 0.1)
				(type default)
			)
			(layer "B.Fab")
		)
		(fp_line
			(start -0.3048 0.9906)
			(end -0.3048 -0.1016)
			(stroke
				(width 0.1)
				(type default)
			)
			(layer "B.Fab")
		)
		(fp_line
			(start 0.3048 -0.1016)
			(end 0.3048 0.9906)
			(stroke
				(width 0.1)
				(type default)
			)
			(layer "B.Fab")
		)
		(fp_line
			(start 0.3048 0.9906)
			(end -0.3048 0.9906)
			(stroke
				(width 0.1)
				(type default)
			)
			(layer "B.Fab")
		)
		(pad "1" smd rect
			(at 0 0 180)
			(size 0.508 0.508)
			(layers "B.Cu" "B.Mask" "B.Paste")
			(net "P3E_CPU0_PE3_OCP_TXN<7>")
		)
		(pad "2" smd rect
			(at 0 0.889 180)
			(size 0.508 0.508)
			(layers "B.Cu" "B.Mask" "B.Paste")
			(net "P3E_OCP_CPU0_PE3_C_TXN<7>")
		)
		(zone
			(layer "B.Cu")
			(hatch none 0.5)
			(connect_pads
				(clearance 0)
			)
			(min_thickness 0.25)
			(keepout
				(tracks allowed)
				(vias not_allowed)
				(pads allowed)
				(copperpour not_allowed)
				(footprints allowed)
			)
			(placement
				(enabled no)
				(sheetname "")
			)
			(fill
				(thermal_gap 0.5)
				(thermal_bridge_width 0.5)
				(island_removal_mode 0)
			)
			(polygon
				(pts
					(xy 441.6044 -52.0446) (xy 441.0964 -52.0446) (xy 441.0964 -51.6636) (xy 441.6044 -51.6636)
				)
			)
		)
		(zone
			(layer "B.Cu")
			(hatch none 0.5)
			(connect_pads
				(clearance 0)
			)
			(min_thickness 0.25)
			(keepout
				(tracks not_allowed)
				(vias allowed)
				(pads allowed)
				(copperpour not_allowed)
				(footprints allowed)
			)
			(placement
				(enabled no)
				(sheetname "")
			)
			(fill
				(thermal_gap 0.5)
				(thermal_bridge_width 0.5)
				(island_removal_mode 0)
			)
			(polygon
				(pts
					(xy 441.6044 -51.6636) (xy 441.0964 -51.6636) (xy 441.0964 -52.0446) (xy 441.6044 -52.0446)
				)
			)
		)
	)
	(footprint ""
		(layer "B.Cu")
		(at 472.059 -112.141 -90)
		(property "Reference" "R1M18"
			(at 0 0 90)
			(layer "B.SilkS")
			(hide yes)
			(effects
				(font
					(size 1.27 1.27)
				)
				(justify mirror)
			)
		)
		(property "Value" ""
			(at 0 0 90)
			(layer "B.Fab")
			(effects
				(font
					(size 1.27 1.27)
				)
				(justify mirror)
			)
		)
		(duplicate_pad_numbers_are_jumpers no)
		(fp_poly
			(pts
				(xy 0.2794 -0.1016) (xy -0.2794 -0.1016) (xy -0.2794 0.9906) (xy 0.2794 0.9906)
			)
			(stroke
				(width 0)
				(type default)
			)
			(fill no)
			(layer "B.CrtYd")
		)
		(fp_line
			(start -0.2794 0.9906)
			(end -0.2794 -0.1016)
			(stroke
				(width 0.1)
				(type default)
			)
			(layer "B.Fab")
		)
		(fp_line
			(start 0.2794 0.9906)
			(end -0.2794 0.9906)
			(stroke
				(width 0.1)
				(type default)
			)
			(layer "B.Fab")
		)
		(fp_line
			(start -0.2794 -0.1016)
			(end 0.2794 -0.1016)
			(stroke
				(width 0.1)
				(type default)
			)
			(layer "B.Fab")
		)
		(fp_line
			(start 0.2794 -0.1016)
			(end 0.2794 0.9906)
			(stroke
				(width 0.1)
				(type default)
			)
			(layer "B.Fab")
		)
		(pad "1" smd rect
			(at 0 0 90)
			(size 0.508 0.508)
			(layers "B.Cu" "B.Mask" "B.Paste")
			(net "RMII_BMC_OCP_RXER_R")
		)
		(pad "2" smd rect
			(at 0 0.889 90)
			(size 0.508 0.508)
			(layers "B.Cu" "B.Mask" "B.Paste")
			(net "RMII_BMC_OCP_RXER")
		)
		(zone
			(layer "B.Cu")
			(hatch none 0.5)
			(connect_pads
				(clearance 0)
			)
			(min_thickness 0.25)
			(keepout
				(tracks not_allowed)
				(vias allowed)
				(pads allowed)
				(copperpour not_allowed)
				(footprints allowed)
			)
			(placement
				(enabled no)
				(sheetname "")
			)
			(fill
				(thermal_gap 0.5)
				(thermal_bridge_width 0.5)
				(island_removal_mode 0)
			)
			(polygon
				(pts
					(xy 471.424 -111.887) (xy 471.424 -112.395) (xy 471.805 -112.395) (xy 471.805 -111.887)
				)
			)
		)
		(zone
			(layer "B.Cu")
			(hatch none 0.5)
			(connect_pads
				(clearance 0)
			)
			(min_thickness 0.25)
			(keepout
				(tracks allowed)
				(vias not_allowed)
				(pads allowed)
				(copperpour not_allowed)
				(footprints allowed)
			)
			(placement
				(enabled no)
				(sheetname "")
			)
			(fill
				(thermal_gap 0.5)
				(thermal_bridge_width 0.5)
				(island_removal_mode 0)
			)
			(polygon
				(pts
					(xy 471.805 -111.887) (xy 471.805 -112.395) (xy 471.424 -112.395) (xy 471.424 -111.887)
				)
			)
		)
	)
	(footprint ""
		(layer "B.Cu")
		(at 405.726646 -26.489152)
		(property "Reference" "R1U38"
			(at 0 0 0)
			(layer "B.SilkS")
			(hide yes)
			(effects
				(font
					(size 1.27 1.27)
				)
				(justify mirror)
			)
		)
		(property "Value" ""
			(at 0 0 0)
			(layer "B.Fab")
			(effects
				(font
					(size 1.27 1.27)
				)
				(justify mirror)
			)
		)
		(duplicate_pad_numbers_are_jumpers no)
		(fp_poly
			(pts
				(xy 0.2794 -0.1016) (xy -0.2794 -0.1016) (xy -0.2794 0.9906) (xy 0.2794 0.9906)
			)
			(stroke
				(width 0)
				(type default)
			)
			(fill no)
			(layer "B.CrtYd")
		)
		(fp_line
			(start -0.2794 -0.1016)
			(end 0.2794 -0.1016)
			(stroke
				(width 0.1)
				(type default)
			)
			(layer "B.Fab")
		)
		(fp_line
			(start -0.2794 0.9906)
			(end -0.2794 -0.1016)
			(stroke
				(width 0.1)
				(type default)
			)
			(layer "B.Fab")
		)
		(fp_line
			(start 0.2794 -0.1016)
			(end 0.2794 0.9906)
			(stroke
				(width 0.1)
				(type default)
			)
			(layer "B.Fab")
		)
		(fp_line
			(start 0.2794 0.9906)
			(end -0.2794 0.9906)
			(stroke
				(width 0.1)
				(type default)
			)
			(layer "B.Fab")
		)
		(pad "1" smd rect
			(at 0 0 180)
			(size 0.508 0.508)
			(layers "B.Cu" "B.Mask" "B.Paste")
			(net "A_P3V3_STBY_SCALED")
		)
		(pad "2" smd rect
			(at 0 0.889 180)
			(size 0.508 0.508)
			(layers "B.Cu" "B.Mask" "B.Paste")
			(net "GND")
		)
		(zone
			(layer "B.Cu")
			(hatch none 0.5)
			(connect_pads
				(clearance 0)
			)
			(min_thickness 0.25)
			(keepout
				(tracks allowed)
				(vias not_allowed)
				(pads allowed)
				(copperpour not_allowed)
				(footprints allowed)
			)
			(placement
				(enabled no)
				(sheetname "")
			)
			(fill
				(thermal_gap 0.5)
				(thermal_bridge_width 0.5)
				(island_removal_mode 0)
			)
			(polygon
				(pts
					(xy 405.980646 -26.235152) (xy 405.472646 -26.235152) (xy 405.472646 -25.854152) (xy 405.980646 -25.854152)
				)
			)
		)
		(zone
			(layer "B.Cu")
			(hatch none 0.5)
			(connect_pads
				(clearance 0)
			)
			(min_thickness 0.25)
			(keepout
				(tracks not_allowed)
				(vias allowed)
				(pads allowed)
				(copperpour not_allowed)
				(footprints allowed)
			)
			(placement
				(enabled no)
				(sheetname "")
			)
			(fill
				(thermal_gap 0.5)
				(thermal_bridge_width 0.5)
				(island_removal_mode 0)
			)
			(polygon
				(pts
					(xy 405.980646 -25.854152) (xy 405.472646 -25.854152) (xy 405.472646 -26.235152) (xy 405.980646 -26.235152)
				)
			)
		)
	)
	(footprint ""
		(layer "B.Cu")
		(at 192.786 -154.559 180)
		(property "Reference" "R6L3"
			(at 0 0 0)
			(layer "B.SilkS")
			(hide yes)
			(effects
				(font
					(size 1.27 1.27)
				)
				(justify mirror)
			)
		)
		(property "Value" ""
			(at 0 0 0)
			(layer "B.Fab")
			(effects
				(font
					(size 1.27 1.27)
				)
				(justify mirror)
			)
		)
		(duplicate_pad_numbers_are_jumpers no)
		(fp_poly
			(pts
				(xy 0.2794 -0.1016) (xy -0.2794 -0.1016) (xy -0.2794 0.9906) (xy 0.2794 0.9906)
			)
			(stroke
				(width 0)
				(type default)
			)
			(fill no)
			(layer "B.CrtYd")
		)
		(fp_line
			(start 0.2794 0.9906)
			(end -0.2794 0.9906)
			(stroke
				(width 0.1)
				(type default)
			)
			(layer "B.Fab")
		)
		(fp_line
			(start 0.2794 -0.1016)
			(end 0.2794 0.9906)
			(stroke
				(width 0.1)
				(type default)
			)
			(layer "B.Fab")
		)
		(fp_line
			(start -0.2794 0.9906)
			(end -0.2794 -0.1016)
			(stroke
				(width 0.1)
				(type default)
			)
			(layer "B.Fab")
		)
		(fp_line
			(start -0.2794 -0.1016)
			(end 0.2794 -0.1016)
			(stroke
				(width 0.1)
				(type default)
			)
			(layer "B.Fab")
		)
		(pad "1" smd rect
			(at 0 0)
			(size 0.508 0.508)
			(layers "B.Cu" "B.Mask" "B.Paste")
			(net "M_F_CPU_VREF")
		)
		(pad "2" smd rect
			(at 0 0.889)
			(size 0.508 0.508)
			(layers "B.Cu" "B.Mask" "B.Paste")
			(net "M_F_VREF")
		)
		(zone
			(layer "B.Cu")
			(hatch none 0.5)
			(connect_pads
				(clearance 0)
			)
			(min_thickness 0.25)
			(keepout
				(tracks not_allowed)
				(vias allowed)
				(pads allowed)
				(copperpour not_allowed)
				(footprints allowed)
			)
			(placement
				(enabled no)
				(sheetname "")
			)
			(fill
				(thermal_gap 0.5)
				(thermal_bridge_width 0.5)
				(island_removal_mode 0)
			)
			(polygon
				(pts
					(xy 192.532 -155.194) (xy 193.04 -155.194) (xy 193.04 -154.813) (xy 192.532 -154.813)
				)
			)
		)
		(zone
			(layer "B.Cu")
			(hatch none 0.5)
			(connect_pads
				(clearance 0)
			)
			(min_thickness 0.25)
			(keepout
				(tracks allowed)
				(vias not_allowed)
				(pads allowed)
				(copperpour not_allowed)
				(footprints allowed)
			)
			(placement
				(enabled no)
				(sheetname "")
			)
			(fill
				(thermal_gap 0.5)
				(thermal_bridge_width 0.5)
				(island_removal_mode 0)
			)
			(polygon
				(pts
					(xy 192.532 -154.813) (xy 193.04 -154.813) (xy 193.04 -155.194) (xy 192.532 -155.194)
				)
			)
		)
	)
	(footprint ""
		(layer "B.Cu")
		(at 444.45174 -20.85848 180)
		(property "Reference" "C8W2"
			(at 0.8382 -0.67818 180)
			(unlocked yes)
			(layer "B.SilkS")
			(effects
				(font
					(size 0.4064 0.254)
					(thickness 0.1524)
				)
				(justify left mirror)
			)
		)
		(property "Value" ""
			(at 0 0 0)
			(layer "B.Fab")
			(effects
				(font
					(size 1.27 1.27)
				)
				(justify mirror)
			)
		)
		(duplicate_pad_numbers_are_jumpers no)
		(fp_poly
			(pts
				(xy -0.3048 -0.1016) (xy -0.3048 0.9906) (xy 0.3048 0.9906) (xy 0.3048 -0.1016)
			)
			(stroke
				(width 0)
				(type default)
			)
			(fill no)
			(layer "B.CrtYd")
		)
		(fp_line
			(start 0.3048 0.9906)
			(end -0.3048 0.9906)
			(stroke
				(width 0.1)
				(type default)
			)
			(layer "B.Fab")
		)
		(fp_line
			(start 0.3048 -0.1016)
			(end 0.3048 0.9906)
			(stroke
				(width 0.1)
				(type default)
			)
			(layer "B.Fab")
		)
		(fp_line
			(start -0.3048 0.9906)
			(end -0.3048 -0.1016)
			(stroke
				(width 0.1)
				(type default)
			)
			(layer "B.Fab")
		)
		(fp_line
			(start -0.3048 -0.1016)
			(end 0.3048 -0.1016)
			(stroke
				(width 0.1)
				(type default)
			)
			(layer "B.Fab")
		)
		(pad "1" smd rect
			(at 0 0)
			(size 0.508 0.508)
			(layers "B.Cu" "B.Mask" "B.Paste")
			(net "P5V_STBY")
		)
		(pad "2" smd rect
			(at 0 0.889)
			(size 0.508 0.508)
			(layers "B.Cu" "B.Mask" "B.Paste")
			(net "GND")
		)
		(zone
			(layer "B.Cu")
			(hatch none 0.5)
			(connect_pads
				(clearance 0)
			)
			(min_thickness 0.25)
			(keepout
				(tracks not_allowed)
				(vias allowed)
				(pads allowed)
				(copperpour not_allowed)
				(footprints allowed)
			)
			(placement
				(enabled no)
				(sheetname "")
			)
			(fill
				(thermal_gap 0.5)
				(thermal_bridge_width 0.5)
				(island_removal_mode 0)
			)
			(polygon
				(pts
					(xy 444.19774 -21.49348) (xy 444.70574 -21.49348) (xy 444.70574 -21.11248) (xy 444.19774 -21.11248)
				)
			)
		)
		(zone
			(layer "B.Cu")
			(hatch none 0.5)
			(connect_pads
				(clearance 0)
			)
			(min_thickness 0.25)
			(keepout
				(tracks allowed)
				(vias not_allowed)
				(pads allowed)
				(copperpour not_allowed)
				(footprints allowed)
			)
			(placement
				(enabled no)
				(sheetname "")
			)
			(fill
				(thermal_gap 0.5)
				(thermal_bridge_width 0.5)
				(island_removal_mode 0)
			)
			(polygon
				(pts
					(xy 444.19774 -21.11248) (xy 444.70574 -21.11248) (xy 444.70574 -21.49348) (xy 444.19774 -21.49348)
				)
			)
		)
	)
	(footprint ""
		(layer "B.Cu")
		(at 447.136266 -22.269196 -90)
		(property "Reference" "R8W4"
			(at 0.8382 -0.67818 270)
			(unlocked yes)
			(layer "B.SilkS")
			(effects
				(font
					(size 0.4064 0.254)
					(thickness 0.1524)
				)
				(justify left mirror)
			)
		)
		(property "Value" ""
			(at 0 0 90)
			(layer "B.Fab")
			(effects
				(font
					(size 1.27 1.27)
				)
				(justify mirror)
			)
		)
		(duplicate_pad_numbers_are_jumpers no)
		(fp_poly
			(pts
				(xy 0.2794 -0.1016) (xy -0.2794 -0.1016) (xy -0.2794 0.9906) (xy 0.2794 0.9906)
			)
			(stroke
				(width 0)
				(type default)
			)
			(fill no)
			(layer "B.CrtYd")
		)
		(fp_line
			(start -0.2794 0.9906)
			(end -0.2794 -0.1016)
			(stroke
				(width 0.1)
				(type default)
			)
			(layer "B.Fab")
		)
		(fp_line
			(start 0.2794 0.9906)
			(end -0.2794 0.9906)
			(stroke
				(width 0.1)
				(type default)
			)
			(layer "B.Fab")
		)
		(fp_line
			(start -0.2794 -0.1016)
			(end 0.2794 -0.1016)
			(stroke
				(width 0.1)
				(type default)
			)
			(layer "B.Fab")
		)
		(fp_line
			(start 0.2794 -0.1016)
			(end 0.2794 0.9906)
			(stroke
				(width 0.1)
				(type default)
			)
			(layer "B.Fab")
		)
		(pad "1" smd rect
			(at 0 0 90)
			(size 0.508 0.508)
			(layers "B.Cu" "B.Mask" "B.Paste")
			(net "SMB_HOST_STBY_LVC3_SDA")
		)
		(pad "2" smd rect
			(at 0 0.889 90)
			(size 0.508 0.508)
			(layers "B.Cu" "B.Mask" "B.Paste")
			(net "SMB_HOST_STBY_LVC3_SDA_R5")
		)
		(zone
			(layer "B.Cu")
			(hatch none 0.5)
			(connect_pads
				(clearance 0)
			)
			(min_thickness 0.25)
			(keepout
				(tracks not_allowed)
				(vias allowed)
				(pads allowed)
				(copperpour not_allowed)
				(footprints allowed)
			)
			(placement
				(enabled no)
				(sheetname "")
			)
			(fill
				(thermal_gap 0.5)
				(thermal_bridge_width 0.5)
				(island_removal_mode 0)
			)
			(polygon
				(pts
					(xy 446.501266 -22.015196) (xy 446.501266 -22.523196) (xy 446.882266 -22.523196) (xy 446.882266 -22.015196)
				)
			)
		)
		(zone
			(layer "B.Cu")
			(hatch none 0.5)
			(connect_pads
				(clearance 0)
			)
			(min_thickness 0.25)
			(keepout
				(tracks allowed)
				(vias not_allowed)
				(pads allowed)
				(copperpour not_allowed)
				(footprints allowed)
			)
			(placement
				(enabled no)
				(sheetname "")
			)
			(fill
				(thermal_gap 0.5)
				(thermal_bridge_width 0.5)
				(island_removal_mode 0)
			)
			(polygon
				(pts
					(xy 446.882266 -22.015196) (xy 446.882266 -22.523196) (xy 446.501266 -22.523196) (xy 446.501266 -22.015196)
				)
			)
		)
	)
)
